(kicad_pcb
	(version 20260206)
	(generator "pcbnew")
	(generator_version "10.0")
	(general
		(thickness 1.6)
		(legacy_teardrops no)
	)
	(paper "A4")
	(title_block
		(title "04192023_DAF0TMB3IC0_F0TG_MB_C_brd_V02_OCP.brd")
		(comment 1 "Grand Teton / footprints 5331-5337 of 8354")
	)
	(layers
		(0 "F.Cu" signal "TOP")
		(4 "In1.Cu" signal "GND")
		(6 "In2.Cu" signal "IN1")
		(8 "In3.Cu" signal "GND1")
		(10 "In4.Cu" signal "IN2")
		(12 "In5.Cu" signal "GND2")
		(14 "In6.Cu" signal "IN3")
		(16 "In7.Cu" signal "GND3")
		(18 "In8.Cu" signal "VCC")
		(20 "In9.Cu" signal "VCC1")
		(22 "In10.Cu" signal "GND4")
		(24 "In11.Cu" signal "IN4")
		(26 "In12.Cu" signal "GND5")
		(28 "In13.Cu" signal "IN5")
		(30 "In14.Cu" signal "GND6")
		(32 "In15.Cu" signal "IN6")
		(34 "In16.Cu" signal "GND7")
		(2 "B.Cu" signal "BOTTOM")
		(9 "F.Adhes" user "F.Adhesive")
		(11 "B.Adhes" user "B.Adhesive")
		(13 "F.Paste" user "Package Geometry/Pastemask Top")
		(15 "B.Paste" user "Package Geometry/Pastemask Bottom")
		(5 "F.SilkS" user "Ref Des/Silkscreen Top")
		(7 "B.SilkS" user "Ref Des/Silkscreen Bottom")
		(1 "F.Mask" user "Board Geometry/Soldermask Top")
		(3 "B.Mask" user "Board Geometry/Soldermask Bottom")
		(17 "Dwgs.User" user "User.Drawings")
		(19 "Cmts.User" user "User.Comments")
		(21 "Eco1.User" user "User.Eco1")
		(23 "Eco2.User" user "User.Eco2")
		(25 "Edge.Cuts" user "Board Geometry/Outline")
		(27 "Margin" user)
		(31 "F.CrtYd" user "Package Geometry/Place Bound Top")
		(29 "B.CrtYd" user "Package Geometry/Place Bound Bottom")
		(35 "F.Fab" user "Ref Des/Assembly Top")
		(33 "B.Fab" user "Ref Des/Assembly Bottom")
	)
	(footprint ""
		(layer "B.Cu")
		(at 104.555544 -412.832296 90)
		(property "Reference" "R4546"
			(at 0 0 90)
			(layer "B.SilkS")
			(hide yes)
			(effects
				(font
					(size 1.27 1.27)
				)
				(justify mirror)
			)
		)
		(property "Value" ""
			(at 0 0 90)
			(layer "B.Fab")
			(effects
				(font
					(size 1.27 1.27)
				)
				(justify mirror)
			)
		)
		(duplicate_pad_numbers_are_jumpers no)
		(fp_line
			(start 0.7874 -0.4064)
			(end -0.7874 -0.4064)
			(stroke
				(width 0.1524)
				(type default)
			)
			(layer "B.SilkS")
		)
		(fp_line
			(start -0.7874 -0.4064)
			(end -0.7874 0.4064)
			(stroke
				(width 0.1524)
				(type default)
			)
			(layer "B.SilkS")
		)
		(fp_line
			(start 0.7874 0.4064)
			(end 0.7874 -0.4064)
			(stroke
				(width 0.1524)
				(type default)
			)
			(layer "B.SilkS")
		)
		(fp_line
			(start -0.7874 0.4064)
			(end 0.7874 0.4064)
			(stroke
				(width 0.1524)
				(type default)
			)
			(layer "B.SilkS")
		)
		(fp_line
			(start 0.67945 -0.305054)
			(end 0.12065 -0.305054)
			(stroke
				(width 0.1)
				(type default)
			)
			(layer "B.Fab")
		)
		(fp_line
			(start 0.12065 -0.305054)
			(end 0.12065 -0.2794)
			(stroke
				(width 0.1)
				(type default)
			)
			(layer "B.Fab")
		)
		(fp_line
			(start -0.12065 -0.3048)
			(end -0.67945 -0.3048)
			(stroke
				(width 0.1)
				(type default)
			)
			(layer "B.Fab")
		)
		(fp_line
			(start -0.67945 -0.3048)
			(end -0.67945 0.3048)
			(stroke
				(width 0.1)
				(type default)
			)
			(layer "B.Fab")
		)
		(fp_line
			(start 0.12065 -0.2794)
			(end -0.12065 -0.2794)
			(stroke
				(width 0.1)
				(type default)
			)
			(layer "B.Fab")
		)
		(fp_line
			(start -0.12065 -0.2794)
			(end -0.12065 -0.3048)
			(stroke
				(width 0.1)
				(type default)
			)
			(layer "B.Fab")
		)
		(fp_line
			(start 0.12065 0.2794)
			(end 0.12065 0.3048)
			(stroke
				(width 0.1)
				(type default)
			)
			(layer "B.Fab")
		)
		(fp_line
			(start -0.120396 0.2794)
			(end 0.12065 0.2794)
			(stroke
				(width 0.1)
				(type default)
			)
			(layer "B.Fab")
		)
		(fp_line
			(start 0.67945 0.3048)
			(end 0.67945 -0.305054)
			(stroke
				(width 0.1)
				(type default)
			)
			(layer "B.Fab")
		)
		(fp_line
			(start 0.12065 0.3048)
			(end 0.67945 0.3048)
			(stroke
				(width 0.1)
				(type default)
			)
			(layer "B.Fab")
		)
		(fp_line
			(start -0.120396 0.3048)
			(end -0.120396 0.2794)
			(stroke
				(width 0.1)
				(type default)
			)
			(layer "B.Fab")
		)
		(fp_line
			(start -0.67945 0.3048)
			(end -0.120396 0.3048)
			(stroke
				(width 0.1)
				(type default)
			)
			(layer "B.Fab")
		)
		(pad "1" smd circle
			(at 0.40005 0 270)
			(size 0 0)
			(layers "B.Cu" "B.Mask" "B.Paste")
			(net "P3V3_AUX")
		)
		(pad "2" smd circle
			(at -0.40005 0 270)
			(size 0 0)
			(layers "B.Cu" "B.Mask" "B.Paste")
			(net "HGX_DETECT_N_ISO")
		)
	)
	(footprint ""
		(layer "B.Cu")
		(at 119.801386 -250.892564)
		(property "Reference" "C2296"
			(at 0 0 0)
			(layer "B.SilkS")
			(hide yes)
			(effects
				(font
					(size 1.27 1.27)
				)
				(justify mirror)
			)
		)
		(property "Value" ""
			(at 0 0 0)
			(layer "B.Fab")
			(effects
				(font
					(size 1.27 1.27)
				)
				(justify mirror)
			)
		)
		(duplicate_pad_numbers_are_jumpers no)
		(fp_line
			(start -0.7874 -0.4064)
			(end -0.7874 0.4064)
			(stroke
				(width 0.1524)
				(type default)
			)
			(layer "B.SilkS")
		)
		(fp_line
			(start -0.7874 0.4064)
			(end 0.7874 0.4064)
			(stroke
				(width 0.1524)
				(type default)
			)
			(layer "B.SilkS")
		)
		(fp_line
			(start 0.7874 -0.4064)
			(end -0.7874 -0.4064)
			(stroke
				(width 0.1524)
				(type default)
			)
			(layer "B.SilkS")
		)
		(fp_line
			(start 0.7874 0.4064)
			(end 0.7874 -0.4064)
			(stroke
				(width 0.1524)
				(type default)
			)
			(layer "B.SilkS")
		)
		(fp_line
			(start -0.67945 -0.3048)
			(end -0.67945 0.3048)
			(stroke
				(width 0.1)
				(type default)
			)
			(layer "B.Fab")
		)
		(fp_line
			(start -0.67945 0.3048)
			(end -0.120396 0.3048)
			(stroke
				(width 0.1)
				(type default)
			)
			(layer "B.Fab")
		)
		(fp_line
			(start -0.12065 -0.3048)
			(end -0.67945 -0.3048)
			(stroke
				(width 0.1)
				(type default)
			)
			(layer "B.Fab")
		)
		(fp_line
			(start -0.12065 -0.2794)
			(end -0.12065 -0.3048)
			(stroke
				(width 0.1)
				(type default)
			)
			(layer "B.Fab")
		)
		(fp_line
			(start -0.120396 0.2794)
			(end 0.12065 0.2794)
			(stroke
				(width 0.1)
				(type default)
			)
			(layer "B.Fab")
		)
		(fp_line
			(start -0.120396 0.3048)
			(end -0.120396 0.2794)
			(stroke
				(width 0.1)
				(type default)
			)
			(layer "B.Fab")
		)
		(fp_line
			(start 0.12065 -0.305054)
			(end 0.12065 -0.2794)
			(stroke
				(width 0.1)
				(type default)
			)
			(layer "B.Fab")
		)
		(fp_line
			(start 0.12065 -0.2794)
			(end -0.12065 -0.2794)
			(stroke
				(width 0.1)
				(type default)
			)
			(layer "B.Fab")
		)
		(fp_line
			(start 0.12065 0.2794)
			(end 0.12065 0.3048)
			(stroke
				(width 0.1)
				(type default)
			)
			(layer "B.Fab")
		)
		(fp_line
			(start 0.12065 0.3048)
			(end 0.67945 0.3048)
			(stroke
				(width 0.1)
				(type default)
			)
			(layer "B.Fab")
		)
		(fp_line
			(start 0.67945 -0.305054)
			(end 0.12065 -0.305054)
			(stroke
				(width 0.1)
				(type default)
			)
			(layer "B.Fab")
		)
		(fp_line
			(start 0.67945 0.3048)
			(end 0.67945 -0.305054)
			(stroke
				(width 0.1)
				(type default)
			)
			(layer "B.Fab")
		)
		(pad "1" smd circle
			(at 0.40005 0 180)
			(size 0 0)
			(layers "B.Cu" "B.Mask" "B.Paste")
			(net "PVDDCR_CPU0_P1")
		)
		(pad "2" smd circle
			(at -0.40005 0 180)
			(size 0 0)
			(layers "B.Cu" "B.Mask" "B.Paste")
			(net "GND")
		)
	)
	(footprint ""
		(layer "B.Cu")
		(at 125.389386 -249.368564)
		(property "Reference" "C2313"
			(at 0 0 0)
			(layer "B.SilkS")
			(hide yes)
			(effects
				(font
					(size 1.27 1.27)
				)
				(justify mirror)
			)
		)
		(property "Value" ""
			(at 0 0 0)
			(layer "B.Fab")
			(effects
				(font
					(size 1.27 1.27)
				)
				(justify mirror)
			)
		)
		(duplicate_pad_numbers_are_jumpers no)
		(fp_line
			(start -0.7874 -0.4064)
			(end -0.7874 0.4064)
			(stroke
				(width 0.1524)
				(type default)
			)
			(layer "B.SilkS")
		)
		(fp_line
			(start -0.7874 0.4064)
			(end 0.7874 0.4064)
			(stroke
				(width 0.1524)
				(type default)
			)
			(layer "B.SilkS")
		)
		(fp_line
			(start 0.7874 -0.4064)
			(end -0.7874 -0.4064)
			(stroke
				(width 0.1524)
				(type default)
			)
			(layer "B.SilkS")
		)
		(fp_line
			(start 0.7874 0.4064)
			(end 0.7874 -0.4064)
			(stroke
				(width 0.1524)
				(type default)
			)
			(layer "B.SilkS")
		)
		(fp_line
			(start -0.67945 -0.3048)
			(end -0.67945 0.3048)
			(stroke
				(width 0.1)
				(type default)
			)
			(layer "B.Fab")
		)
		(fp_line
			(start -0.67945 0.3048)
			(end -0.120396 0.3048)
			(stroke
				(width 0.1)
				(type default)
			)
			(layer "B.Fab")
		)
		(fp_line
			(start -0.12065 -0.3048)
			(end -0.67945 -0.3048)
			(stroke
				(width 0.1)
				(type default)
			)
			(layer "B.Fab")
		)
		(fp_line
			(start -0.12065 -0.2794)
			(end -0.12065 -0.3048)
			(stroke
				(width 0.1)
				(type default)
			)
			(layer "B.Fab")
		)
		(fp_line
			(start -0.120396 0.2794)
			(end 0.12065 0.2794)
			(stroke
				(width 0.1)
				(type default)
			)
			(layer "B.Fab")
		)
		(fp_line
			(start -0.120396 0.3048)
			(end -0.120396 0.2794)
			(stroke
				(width 0.1)
				(type default)
			)
			(layer "B.Fab")
		)
		(fp_line
			(start 0.12065 -0.305054)
			(end 0.12065 -0.2794)
			(stroke
				(width 0.1)
				(type default)
			)
			(layer "B.Fab")
		)
		(fp_line
			(start 0.12065 -0.2794)
			(end -0.12065 -0.2794)
			(stroke
				(width 0.1)
				(type default)
			)
			(layer "B.Fab")
		)
		(fp_line
			(start 0.12065 0.2794)
			(end 0.12065 0.3048)
			(stroke
				(width 0.1)
				(type default)
			)
			(layer "B.Fab")
		)
		(fp_line
			(start 0.12065 0.3048)
			(end 0.67945 0.3048)
			(stroke
				(width 0.1)
				(type default)
			)
			(layer "B.Fab")
		)
		(fp_line
			(start 0.67945 -0.305054)
			(end 0.12065 -0.305054)
			(stroke
				(width 0.1)
				(type default)
			)
			(layer "B.Fab")
		)
		(fp_line
			(start 0.67945 0.3048)
			(end 0.67945 -0.305054)
			(stroke
				(width 0.1)
				(type default)
			)
			(layer "B.Fab")
		)
		(pad "1" smd circle
			(at 0.40005 0 180)
			(size 0 0)
			(layers "B.Cu" "B.Mask" "B.Paste")
			(net "PVDDCR_CPU0_P1")
		)
		(pad "2" smd circle
			(at -0.40005 0 180)
			(size 0 0)
			(layers "B.Cu" "B.Mask" "B.Paste")
			(net "GND")
		)
	)
	(footprint ""
		(layer "B.Cu")
		(at 81.246218 -388.011162 -90)
		(property "Reference" "C322"
			(at 0 0 90)
			(layer "B.SilkS")
			(hide yes)
			(effects
				(font
					(size 1.27 1.27)
				)
				(justify mirror)
			)
		)
		(property "Value" ""
			(at 0 0 90)
			(layer "B.Fab")
			(effects
				(font
					(size 1.27 1.27)
				)
				(justify mirror)
			)
		)
		(duplicate_pad_numbers_are_jumpers no)
		(fp_line
			(start -0.299974 0.150114)
			(end 0.299974 0.150114)
			(stroke
				(width 0.1)
				(type default)
			)
			(layer "B.Fab")
		)
		(fp_line
			(start 0.299974 0.150114)
			(end 0.299974 -0.150114)
			(stroke
				(width 0.1)
				(type default)
			)
			(layer "B.Fab")
		)
		(fp_line
			(start -0.299974 -0.150114)
			(end -0.299974 0.150114)
			(stroke
				(width 0.1)
				(type default)
			)
			(layer "B.Fab")
		)
		(fp_line
			(start 0.299974 -0.150114)
			(end -0.299974 -0.150114)
			(stroke
				(width 0.1)
				(type default)
			)
			(layer "B.Fab")
		)
		(pad "1" smd rect
			(at 0.2667 0 90)
			(size 0.3048 0.381)
			(layers "B.Cu" "B.Mask" "B.Paste")
			(net "P0V9_CPU1_RT1_2A")
		)
		(pad "2" smd rect
			(at -0.2667 0 90)
			(size 0.3048 0.381)
			(layers "B.Cu" "B.Mask" "B.Paste")
			(net "GND")
		)
	)
	(footprint ""
		(layer "B.Cu")
		(at 10.066782 -412.291784)
		(property "Reference" "PR6815"
			(at 0 0 0)
			(layer "B.SilkS")
			(hide yes)
			(effects
				(font
					(size 1.27 1.27)
				)
				(justify mirror)
			)
		)
		(property "Value" ""
			(at 0 0 0)
			(layer "B.Fab")
			(effects
				(font
					(size 1.27 1.27)
				)
				(justify mirror)
			)
		)
		(duplicate_pad_numbers_are_jumpers no)
		(fp_line
			(start -0.7874 -0.4064)
			(end -0.7874 0.4064)
			(stroke
				(width 0.1524)
				(type default)
			)
			(layer "B.SilkS")
		)
		(fp_line
			(start -0.7874 0.4064)
			(end 0.7874 0.4064)
			(stroke
				(width 0.1524)
				(type default)
			)
			(layer "B.SilkS")
		)
		(fp_line
			(start 0.7874 -0.4064)
			(end -0.7874 -0.4064)
			(stroke
				(width 0.1524)
				(type default)
			)
			(layer "B.SilkS")
		)
		(fp_line
			(start 0.7874 0.4064)
			(end 0.7874 -0.4064)
			(stroke
				(width 0.1524)
				(type default)
			)
			(layer "B.SilkS")
		)
		(fp_line
			(start -0.67945 -0.3048)
			(end -0.67945 0.3048)
			(stroke
				(width 0.1)
				(type default)
			)
			(layer "B.Fab")
		)
		(fp_line
			(start -0.67945 0.3048)
			(end -0.120396 0.3048)
			(stroke
				(width 0.1)
				(type default)
			)
			(layer "B.Fab")
		)
		(fp_line
			(start -0.12065 -0.3048)
			(end -0.67945 -0.3048)
			(stroke
				(width 0.1)
				(type default)
			)
			(layer "B.Fab")
		)
		(fp_line
			(start -0.12065 -0.2794)
			(end -0.12065 -0.3048)
			(stroke
				(width 0.1)
				(type default)
			)
			(layer "B.Fab")
		)
		(fp_line
			(start -0.120396 0.2794)
			(end 0.12065 0.2794)
			(stroke
				(width 0.1)
				(type default)
			)
			(layer "B.Fab")
		)
		(fp_line
			(start -0.120396 0.3048)
			(end -0.120396 0.2794)
			(stroke
				(width 0.1)
				(type default)
			)
			(layer "B.Fab")
		)
		(fp_line
			(start 0.12065 -0.305054)
			(end 0.12065 -0.2794)
			(stroke
				(width 0.1)
				(type default)
			)
			(layer "B.Fab")
		)
		(fp_line
			(start 0.12065 -0.2794)
			(end -0.12065 -0.2794)
			(stroke
				(width 0.1)
				(type default)
			)
			(layer "B.Fab")
		)
		(fp_line
			(start 0.12065 0.2794)
			(end 0.12065 0.3048)
			(stroke
				(width 0.1)
				(type default)
			)
			(layer "B.Fab")
		)
		(fp_line
			(start 0.12065 0.3048)
			(end 0.67945 0.3048)
			(stroke
				(width 0.1)
				(type default)
			)
			(layer "B.Fab")
		)
		(fp_line
			(start 0.67945 -0.305054)
			(end 0.12065 -0.305054)
			(stroke
				(width 0.1)
				(type default)
			)
			(layer "B.Fab")
		)
		(fp_line
			(start 0.67945 0.3048)
			(end 0.67945 -0.305054)
			(stroke
				(width 0.1)
				(type default)
			)
			(layer "B.Fab")
		)
		(pad "1" smd circle
			(at 0.40005 0 180)
			(size 0 0)
			(layers "B.Cu" "B.Mask" "B.Paste")
			(net "P0V9_RETIMER_CPU1_TEMP0")
		)
		(pad "2" smd circle
			(at -0.40005 0 180)
			(size 0 0)
			(layers "B.Cu" "B.Mask" "B.Paste")
			(net "GND")
		)
	)
	(footprint ""
		(layer "B.Cu")
		(at 393.637008 -321.179952)
		(property "Reference" "R750"
			(at 0 0 0)
			(layer "B.SilkS")
			(hide yes)
			(effects
				(font
					(size 1.27 1.27)
				)
				(justify mirror)
			)
		)
		(property "Value" ""
			(at 0 0 0)
			(layer "B.Fab")
			(effects
				(font
					(size 1.27 1.27)
				)
				(justify mirror)
			)
		)
		(duplicate_pad_numbers_are_jumpers no)
		(fp_line
			(start -0.7874 -0.4064)
			(end -0.7874 0.4064)
			(stroke
				(width 0.1524)
				(type default)
			)
			(layer "B.SilkS")
		)
		(fp_line
			(start -0.7874 0.4064)
			(end 0.7874 0.4064)
			(stroke
				(width 0.1524)
				(type default)
			)
			(layer "B.SilkS")
		)
		(fp_line
			(start 0.7874 -0.4064)
			(end -0.7874 -0.4064)
			(stroke
				(width 0.1524)
				(type default)
			)
			(layer "B.SilkS")
		)
		(fp_line
			(start 0.7874 0.4064)
			(end 0.7874 -0.4064)
			(stroke
				(width 0.1524)
				(type default)
			)
			(layer "B.SilkS")
		)
		(fp_line
			(start -0.67945 -0.3048)
			(end -0.67945 0.3048)
			(stroke
				(width 0.1)
				(type default)
			)
			(layer "B.Fab")
		)
		(fp_line
			(start -0.67945 0.3048)
			(end -0.120396 0.3048)
			(stroke
				(width 0.1)
				(type default)
			)
			(layer "B.Fab")
		)
		(fp_line
			(start -0.12065 -0.3048)
			(end -0.67945 -0.3048)
			(stroke
				(width 0.1)
				(type default)
			)
			(layer "B.Fab")
		)
		(fp_line
			(start -0.12065 -0.2794)
			(end -0.12065 -0.3048)
			(stroke
				(width 0.1)
				(type default)
			)
			(layer "B.Fab")
		)
		(fp_line
			(start -0.120396 0.2794)
			(end 0.12065 0.2794)
			(stroke
				(width 0.1)
				(type default)
			)
			(layer "B.Fab")
		)
		(fp_line
			(start -0.120396 0.3048)
			(end -0.120396 0.2794)
			(stroke
				(width 0.1)
				(type default)
			)
			(layer "B.Fab")
		)
		(fp_line
			(start 0.12065 -0.305054)
			(end 0.12065 -0.2794)
			(stroke
				(width 0.1)
				(type default)
			)
			(layer "B.Fab")
		)
		(fp_line
			(start 0.12065 -0.2794)
			(end -0.12065 -0.2794)
			(stroke
				(width 0.1)
				(type default)
			)
			(layer "B.Fab")
		)
		(fp_line
			(start 0.12065 0.2794)
			(end 0.12065 0.3048)
			(stroke
				(width 0.1)
				(type default)
			)
			(layer "B.Fab")
		)
		(fp_line
			(start 0.12065 0.3048)
			(end 0.67945 0.3048)
			(stroke
				(width 0.1)
				(type default)
			)
			(layer "B.Fab")
		)
		(fp_line
			(start 0.67945 -0.305054)
			(end 0.12065 -0.305054)
			(stroke
				(width 0.1)
				(type default)
			)
			(layer "B.Fab")
		)
		(fp_line
			(start 0.67945 0.3048)
			(end 0.67945 -0.305054)
			(stroke
				(width 0.1)
				(type default)
			)
			(layer "B.Fab")
		)
		(pad "1" smd circle
			(at 0.40005 0 180)
			(size 0 0)
			(layers "B.Cu" "B.Mask" "B.Paste")
			(net "GND")
		)
		(pad "2" smd circle
			(at -0.40005 0 180)
			(size 0 0)
			(layers "B.Cu" "B.Mask" "B.Paste")
			(net "CLK_ESPI_CPU0_CLK1")
		)
	)
	(footprint ""
		(layer "B.Cu")
		(at 346.026994 -308.517798)
		(property "Reference" "R405"
			(at 0 0 0)
			(layer "B.SilkS")
			(hide yes)
			(effects
				(font
					(size 1.27 1.27)
				)
				(justify mirror)
			)
		)
		(property "Value" ""
			(at 0 0 0)
			(layer "B.Fab")
			(effects
				(font
					(size 1.27 1.27)
				)
				(justify mirror)
			)
		)
		(duplicate_pad_numbers_are_jumpers no)
		(fp_line
			(start -0.7874 -0.4064)
			(end -0.7874 0.4064)
			(stroke
				(width 0.1524)
				(type default)
			)
			(layer "B.SilkS")
		)
		(fp_line
			(start -0.7874 0.4064)
			(end 0.7874 0.4064)
			(stroke
				(width 0.1524)
				(type default)
			)
			(layer "B.SilkS")
		)
		(fp_line
			(start 0.7874 -0.4064)
			(end -0.7874 -0.4064)
			(stroke
				(width 0.1524)
				(type default)
			)
			(layer "B.SilkS")
		)
		(fp_line
			(start 0.7874 0.4064)
			(end 0.7874 -0.4064)
			(stroke
				(width 0.1524)
				(type default)
			)
			(layer "B.SilkS")
		)
		(fp_line
			(start -0.67945 -0.3048)
			(end -0.67945 0.3048)
			(stroke
				(width 0.1)
				(type default)
			)
			(layer "B.Fab")
		)
		(fp_line
			(start -0.67945 0.3048)
			(end -0.120396 0.3048)
			(stroke
				(width 0.1)
				(type default)
			)
			(layer "B.Fab")
		)
		(fp_line
			(start -0.12065 -0.3048)
			(end -0.67945 -0.3048)
			(stroke
				(width 0.1)
				(type default)
			)
			(layer "B.Fab")
		)
		(fp_line
			(start -0.12065 -0.2794)
			(end -0.12065 -0.3048)
			(stroke
				(width 0.1)
				(type default)
			)
			(layer "B.Fab")
		)
		(fp_line
			(start -0.120396 0.2794)
			(end 0.12065 0.2794)
			(stroke
				(width 0.1)
				(type default)
			)
			(layer "B.Fab")
		)
		(fp_line
			(start -0.120396 0.3048)
			(end -0.120396 0.2794)
			(stroke
				(width 0.1)
				(type default)
			)
			(layer "B.Fab")
		)
		(fp_line
			(start 0.12065 -0.305054)
			(end 0.12065 -0.2794)
			(stroke
				(width 0.1)
				(type default)
			)
			(layer "B.Fab")
		)
		(fp_line
			(start 0.12065 -0.2794)
			(end -0.12065 -0.2794)
			(stroke
				(width 0.1)
				(type default)
			)
			(layer "B.Fab")
		)
		(fp_line
			(start 0.12065 0.2794)
			(end 0.12065 0.3048)
			(stroke
				(width 0.1)
				(type default)
			)
			(layer "B.Fab")
		)
		(fp_line
			(start 0.12065 0.3048)
			(end 0.67945 0.3048)
			(stroke
				(width 0.1)
				(type default)
			)
			(layer "B.Fab")
		)
		(fp_line
			(start 0.67945 -0.305054)
			(end 0.12065 -0.305054)
			(stroke
				(width 0.1)
				(type default)
			)
			(layer "B.Fab")
		)
		(fp_line
			(start 0.67945 0.3048)
			(end 0.67945 -0.305054)
			(stroke
				(width 0.1)
				(type default)
			)
			(layer "B.Fab")
		)
		(pad "1" smd circle
			(at 0.40005 0 180)
			(size 0 0)
			(layers "B.Cu" "B.Mask" "B.Paste")
			(net "UART_CPU0_UART0_TX")
		)
		(pad "2" smd circle
			(at -0.40005 0 180)
			(size 0 0)
			(layers "B.Cu" "B.Mask" "B.Paste")
			(net "UART_CPU0_UART0_R_TX")
		)
	)
)
